# T6G (Grand Teton) — schematic netlist excerpt (pin names and nets, part order shuffled) for the footprints in the layout excerpt that follows; sources: Cadence DE-HDL packaged netlist, KiCad conversion of 04192023_DAF0TMB3IC0_F0TG_MB_C_brd_V02_OCP.brd

PR173  Q_RES  0 5% CHIP  pkg 0402LF  page 210 : A = VSENSE_PVDDCR_CPU0_P1_DP ; B = VSENSE_PVDDCR_CPU0_P1_VSEN0
C7008  Q_CAPP  470UF 2.5V 20% SPCAP  pkg SMLF  page 279 : A = P0V9_CPU0_RT0_2A ; B = GND

(kicad_pcb
	(version 20260206)
	(generator "pcbnew")
	(generator_version "10.0")
	(general
		(thickness 1.6)
		(legacy_teardrops no)
	)
	(paper "A4")
	(title_block
		(title "04192023_DAF0TMB3IC0_F0TG_MB_C_brd_V02_OCP.brd")
		(comment 1 "Grand Teton / footprints 6095-6096 of 8354")
	)
	(layers
		(0 "F.Cu" signal "TOP")
		(4 "In1.Cu" signal "GND")
		(6 "In2.Cu" signal "IN1")
		(8 "In3.Cu" signal "GND1")
		(10 "In4.Cu" signal "IN2")
		(12 "In5.Cu" signal "GND2")
		(14 "In6.Cu" signal "IN3")
		(16 "In7.Cu" signal "GND3")
		(18 "In8.Cu" signal "VCC")
		(20 "In9.Cu" signal "VCC1")
		(22 "In10.Cu" signal "GND4")
		(24 "In11.Cu" signal "IN4")
		(26 "In12.Cu" signal "GND5")
		(28 "In13.Cu" signal "IN5")
		(30 "In14.Cu" signal "GND6")
		(32 "In15.Cu" signal "IN6")
		(34 "In16.Cu" signal "GND7")
		(2 "B.Cu" signal "BOTTOM")
		(9 "F.Adhes" user "F.Adhesive")
		(11 "B.Adhes" user "B.Adhesive")
		(13 "F.Paste" user "Package Geometry/Pastemask Top")
		(15 "B.Paste" user "Package Geometry/Pastemask Bottom")
		(5 "F.SilkS" user "Ref Des/Silkscreen Top")
		(7 "B.SilkS" user "Ref Des/Silkscreen Bottom")
		(1 "F.Mask" user "Board Geometry/Soldermask Top")
		(3 "B.Mask" user "Board Geometry/Soldermask Bottom")
		(17 "Dwgs.User" user "User.Drawings")
		(19 "Cmts.User" user "User.Comments")
		(21 "Eco1.User" user "User.Eco1")
		(23 "Eco2.User" user "User.Eco2")
		(25 "Edge.Cuts" user "Board Geometry/Outline")
		(27 "Margin" user)
		(31 "F.CrtYd" user "Package Geometry/Place Bound Top")
		(29 "B.CrtYd" user "Package Geometry/Place Bound Bottom")
		(35 "F.Fab" user "Ref Des/Assembly Top")
		(33 "B.Fab" user "Ref Des/Assembly Bottom")
	)
	(footprint ""
		(layer "B.Cu")
		(at 91.966542 -151.376634 90)
		(property "Reference" "PR173"
			(at 0 0 90)
			(layer "B.SilkS")
			(hide yes)
			(effects
				(font
					(size 1.27 1.27)
				)
				(justify mirror)
			)
		)
		(property "Value" ""
			(at 0 0 90)
			(layer "B.Fab")
			(effects
				(font
					(size 1.27 1.27)
				)
				(justify mirror)
			)
		)
		(duplicate_pad_numbers_are_jumpers no)
		(fp_line
			(start 0.7874 -0.4064)
			(end -0.7874 -0.4064)
			(stroke
				(width 0.1524)
				(type default)
			)
			(layer "B.SilkS")
		)
		(fp_line
			(start -0.7874 -0.4064)
			(end -0.7874 0.4064)
			(stroke
				(width 0.1524)
				(type default)
			)
			(layer "B.SilkS")
		)
		(fp_line
			(start 0.7874 0.4064)
			(end 0.7874 -0.4064)
			(stroke
				(width 0.1524)
				(type default)
			)
			(layer "B.SilkS")
		)
		(fp_line
			(start -0.7874 0.4064)
			(end 0.7874 0.4064)
			(stroke
				(width 0.1524)
				(type default)
			)
			(layer "B.SilkS")
		)
		(fp_line
			(start 0.67945 -0.305054)
			(end 0.12065 -0.305054)
			(stroke
				(width 0.1)
				(type default)
			)
			(layer "B.Fab")
		)
		(fp_line
			(start 0.12065 -0.305054)
			(end 0.12065 -0.2794)
			(stroke
				(width 0.1)
				(type default)
			)
			(layer "B.Fab")
		)
		(fp_line
			(start -0.12065 -0.3048)
			(end -0.67945 -0.3048)
			(stroke
				(width 0.1)
				(type default)
			)
			(layer "B.Fab")
		)
		(fp_line
			(start -0.67945 -0.3048)
			(end -0.67945 0.3048)
			(stroke
				(width 0.1)
				(type default)
			)
			(layer "B.Fab")
		)
		(fp_line
			(start 0.12065 -0.2794)
			(end -0.12065 -0.2794)
			(stroke
				(width 0.1)
				(type default)
			)
			(layer "B.Fab")
		)
		(fp_line
			(start -0.12065 -0.2794)
			(end -0.12065 -0.3048)
			(stroke
				(width 0.1)
				(type default)
			)
			(layer "B.Fab")
		)
		(fp_line
			(start 0.12065 0.2794)
			(end 0.12065 0.3048)
			(stroke
				(width 0.1)
				(type default)
			)
			(layer "B.Fab")
		)
		(fp_line
			(start -0.120396 0.2794)
			(end 0.12065 0.2794)
			(stroke
				(width 0.1)
				(type default)
			)
			(layer "B.Fab")
		)
		(fp_line
			(start 0.67945 0.3048)
			(end 0.67945 -0.305054)
			(stroke
				(width 0.1)
				(type default)
			)
			(layer "B.Fab")
		)
		(fp_line
			(start 0.12065 0.3048)
			(end 0.67945 0.3048)
			(stroke
				(width 0.1)
				(type default)
			)
			(layer "B.Fab")
		)
		(fp_line
			(start -0.120396 0.3048)
			(end -0.120396 0.2794)
			(stroke
				(width 0.1)
				(type default)
			)
			(layer "B.Fab")
		)
		(fp_line
			(start -0.67945 0.3048)
			(end -0.120396 0.3048)
			(stroke
				(width 0.1)
				(type default)
			)
			(layer "B.Fab")
		)
		(pad "1" smd circle
			(at 0.40005 0 270)
			(size 0 0)
			(layers "B.Cu" "B.Mask" "B.Paste")
			(net "VSENSE_PVDDCR_CPU0_P1_DP")
		)
		(pad "2" smd circle
			(at -0.40005 0 270)
			(size 0 0)
			(layers "B.Cu" "B.Mask" "B.Paste")
			(net "VSENSE_PVDDCR_CPU0_P1_VSEN0")
		)
	)
	(footprint ""
		(layer "B.Cu")
		(at 308.49697 -389.49503 180)
		(property "Reference" "C7008"
			(at -1.7399 -2.910332 0)
			(unlocked yes)
			(layer "B.SilkS")
			(effects
				(font
					(size 0.7874 0.5842)
					(thickness 0.1524)
				)
				(justify left mirror)
			)
		)
		(property "Value" ""
			(at 0 0 0)
			(layer "B.Fab")
			(effects
				(font
					(size 1.27 1.27)
				)
				(justify mirror)
			)
		)
		(duplicate_pad_numbers_are_jumpers no)
		(fp_line
			(start 4.84378 -2.150618)
			(end 4.842256 2.163064)
			(stroke
				(width 0.1524)
				(type default)
			)
			(layer "B.SilkS")
		)
		(fp_line
			(start 4.84378 -2.150618)
			(end 4.53898 -2.150618)
			(stroke
				(width 0.1524)
				(type default)
			)
			(layer "B.SilkS")
		)
		(fp_line
			(start 4.83108 2.150364)
			(end 4.447794 2.149348)
			(stroke
				(width 0.1524)
				(type default)
			)
			(layer "B.SilkS")
		)
		(fp_line
			(start 4.69138 -2.150618)
			(end 4.692396 2.161032)
			(stroke
				(width 0.1524)
				(type default)
			)
			(layer "B.SilkS")
		)
		(fp_line
			(start 4.53898 2.15011)
			(end 4.53898 -2.15011)
			(stroke
				(width 0.1524)
				(type default)
			)
			(layer "B.SilkS")
		)
		(fp_line
			(start 4.53898 -2.15011)
			(end -4.53898 -2.15011)
			(stroke
				(width 0.1524)
				(type default)
			)
			(layer "B.SilkS")
		)
		(fp_line
			(start 4.53898 -2.150618)
			(end 4.539742 2.152142)
			(stroke
				(width 0.1524)
				(type default)
			)
			(layer "B.SilkS")
		)
		(fp_line
			(start -4.53898 2.15011)
			(end 4.53898 2.15011)
			(stroke
				(width 0.1524)
				(type default)
			)
			(layer "B.SilkS")
		)
		(fp_line
			(start -4.53898 -2.15011)
			(end -4.53898 2.15011)
			(stroke
				(width 0.1524)
				(type default)
			)
			(layer "B.SilkS")
		)
		(fp_line
			(start 3.64998 2.15011)
			(end 3.64998 -2.15011)
			(stroke
				(width 0.1)
				(type default)
			)
			(layer "B.Fab")
		)
		(fp_line
			(start 3.64998 -2.15011)
			(end -3.64998 -2.15011)
			(stroke
				(width 0.1)
				(type default)
			)
			(layer "B.Fab")
		)
		(fp_line
			(start -3.64998 2.15011)
			(end 3.64998 2.15011)
			(stroke
				(width 0.1)
				(type default)
			)
			(layer "B.Fab")
		)
		(fp_line
			(start -3.64998 -2.15011)
			(end -3.64998 2.15011)
			(stroke
				(width 0.1)
				(type default)
			)
			(layer "B.Fab")
		)
		(fp_text user "+"
			(at 4.327652 -3.143758 180)
			(unlocked yes)
			(layer "B.SilkS")
			(effects
				(font
					(size 1.905 1.4224)
					(thickness 0.1524)
				)
				(justify left mirror)
			)
		)
		(fp_text user "-"
			(at -2.969514 -2.667508 180)
			(unlocked yes)
			(layer "B.SilkS")
			(effects
				(font
					(size 1.905 1.4224)
					(thickness 0.1524)
				)
				(justify left mirror)
			)
		)
		(fp_text user "+"
			(at 6.214872 -0.337058 180)
			(unlocked yes)
			(layer "B.Fab")
			(effects
				(font
					(size 1.905 1.4224)
					(thickness 0.1524)
				)
				(justify left mirror)
			)
		)
		(fp_text user "-"
			(at -4.313174 -0.094488 180)
			(unlocked yes)
			(layer "B.Fab")
			(effects
				(font
					(size 1.905 1.4224)
					(thickness 0.1524)
				)
				(justify left mirror)
			)
		)
		(pad "1" smd rect
			(at 3.199892 0)
			(size 2.413 2.8194)
			(layers "B.Cu" "B.Mask" "B.Paste")
			(net "P0V9_CPU0_RT0_2A")
		)
		(pad "2" smd rect
			(at -3.199892 0)
			(size 2.413 2.8194)
			(layers "B.Cu" "B.Mask" "B.Paste")
			(net "GND")
		)
	)
)
